# S9S_MB_2U (Grand Teton) — schematic netlist excerpt (pin names and nets, part order shuffled) for the footprints in the layout excerpt that follows; sources: Cadence DE-HDL packaged netlist, KiCad conversion of 03242023_DA0F0TMBIJ0_F0T_Motherboard_J_brd_V01_OCP.brd

J9  SCONN288_ADR50017P130CC  SCONN288_ADR50017-P130CC IO  pkg DDR288S_1-1VXB  page 90
  VIN_BULK0  = P12V_S3_AUX_CPU0_NVDIMM
  RFU0  = TP_CHE_CPU0_DIMM1_FRU_0
  VIN_MGMT  = P3V3_AUX
  HSCL  = I3C_SPD_DDREFGH_CPU0_LVC1_SCL_R
  HSDA  = I3C_SPD_DDREFGH_CPU0_LVC1_SDA
  VSS0  = GND
  DQ0_A  = M_E_CPU0_SA_DQ<0>
  VSS1  = GND
  DQ1_A  = M_E_CPU0_SA_DQ<1>
  VSS2  = GND
  DQS0_A_T  = M_E_CPU0_SA_DQS_DP<0>
  DQS0_A_C  = M_E_CPU0_SA_DQS_DN<0>
  VSS3  = GND
  DQ4_A  = M_E_CPU0_SA_DQ<4>
  VSS4  = GND
  DQ5_A  = M_E_CPU0_SA_DQ<5>
  VSS5  = GND
  DQ8_A  = M_E_CPU0_SA_DQ<8>
  VSS6  = GND
  DQ9_A  = M_E_CPU0_SA_DQ<9>
  VSS7  = GND
  DQS1_A_T  = M_E_CPU0_SA_DQS_DP<1>
  DQS1_A_C  = M_E_CPU0_SA_DQS_DN<1>
  VSS8  = GND
  DQ12_A  = M_E_CPU0_SA_DQ<12>
  VSS9  = GND
  DQ13_A  = M_E_CPU0_SA_DQ<13>
  VSS10  = GND
  DQ16_A  = M_E_CPU0_SA_DQ<16>
  VSS11  = GND
  DQ17_A  = M_E_CPU0_SA_DQ<17>
  VSS12  = GND
  DQS2_A_T  = M_E_CPU0_SA_DQS_DP<2>
  DQS2_A_C  = M_E_CPU0_SA_DQS_DN<2>
  VSS13  = GND
  DQ20_A  = M_E_CPU0_SA_DQ<20>
  VSS14  = GND
  DQ21_A  = M_E_CPU0_SA_DQ<21>
  VSS15  = GND
  DQ24_A  = M_E_CPU0_SA_DQ<24>
  VSS16  = GND
  DQ25_A  = M_E_CPU0_SA_DQ<25>
  VSS17  = GND
  DQS3_A_T  = M_E_CPU0_SA_DQS_DP<3>
  DQS3_A_C  = M_E_CPU0_SA_DQS_DN<3>
  VSS18  = GND
  DQ28_A  = M_E_CPU0_SA_DQ<28>
  VSS19  = GND
  DQ29_A  = M_E_CPU0_SA_DQ<29>
  VSS20  = GND
  CB0_A  = M_E_CPU0_SA_CB<0>
  VSS21  = GND
  CB1_A  = M_E_CPU0_SA_CB<1>
  VSS22  = GND
  DQS4_A_T  = M_E_CPU0_SA_DQS_DP<4>
  DQS4_A_C  = M_E_CPU0_SA_DQS_DN<4>
  VSS23  = GND
  CB4_A  = M_E_CPU0_SA_CB<4>
  VSS24  = GND
  CB5_A  = M_E_CPU0_SA_CB<5>
  VSS25  = GND
  ALERT_N  = M_E_CPU0_ALERT_N
  VSS26  = GND
  CS0_A_N  = M_E_CPU0_SA_CS_N<0>
  VSS27  = GND
  CA0_A  = M_E_CPU0_SA_CA<0>
  VSS28  = GND
  CA2_A  = M_E_CPU0_SA_CA<2>
  VSS29  = GND
  CA4_A  = M_E_CPU0_SA_CA<4>
  VSS30  = GND
  CA6_A  = M_E_CPU0_SA_CA<6>
  VSS31  = GND
  PAR_A  = M_E_CPU0_SA_PAR
  VSS32  = GND
  CA0_B  = M_E_CPU0_SB_CA<0>
  VSS33  = GND
  CA2_B  = M_E_CPU0_SB_CA<2>
  VSS34  = GND
  CA4_B  = M_E_CPU0_SB_CA<4>
  VSS35  = GND
  CA6_B  = M_E_CPU0_SB_CA<6>
  VSS36  = GND
  CS0_B_N  = M_E_CPU0_SB_CS_N<0>
  VSS37  = GND
  \lbd||rsp_a_n\  = M_E_CPU0_SA_RSP<0>
  \lbs||rsp_b_n\  = M_E_CPU0_SB_RSP<0>
  VSS38  = GND
  CB4_B  = M_E_CPU0_SB_CB<4>
  VSS39  = GND
  CB5_B  = M_E_CPU0_SB_CB<5>
  VSS40  = GND
  \dqs9_b_t||tdqs9_b_t||dbi4_b_n\  = M_E_CPU0_SB_DQS_DP<9>
  \dqs9_b_c||tdqs9_b_c\  = M_E_CPU0_SB_DQS_DN<9>
  VSS41  = GND
  CB0_B  = M_E_CPU0_SB_CB<0>
  VSS42  = GND
  CB1_B  = M_E_CPU0_SB_CB<1>
  VSS43  = GND
  DQ0_B  = M_E_CPU0_SB_DQ<0>
  VSS44  = GND
  DQ1_B  = M_E_CPU0_SB_DQ<1>
  VSS45  = GND
  DQS0_B_T  = M_E_CPU0_SB_DQS_DP<0>
  DQS0_B_C  = M_E_CPU0_SB_DQS_DN<0>
  VSS46  = GND
  DQ4_B  = M_E_CPU0_SB_DQ<4>
  VSS47  = GND
  DQ5_B  = M_E_CPU0_SB_DQ<5>
  VSS48  = GND
  DQ8_B  = M_E_CPU0_SB_DQ<8>
  VSS49  = GND
  DQ9_B  = M_E_CPU0_SB_DQ<9>
  VSS50  = GND
  DQS1_B_T  = M_E_CPU0_SB_DQS_DP<1>
  DQS1_B_C  = M_E_CPU0_SB_DQS_DN<1>
  VSS51  = GND
  DQ12_B  = M_E_CPU0_SB_DQ<12>
  VSS52  = GND
  DQ13_B  = M_E_CPU0_SB_DQ<13>
  VSS53  = GND
  DQ16_B  = M_E_CPU0_SB_DQ<16>
  VSS54  = GND
  DQ17_B  = M_E_CPU0_SB_DQ<17>
  VSS55  = GND
  DQS2_B_T  = M_E_CPU0_SB_DQS_DP<2>
  DQS2_B_C  = M_E_CPU0_SB_DQS_DN<2>
  VSS56  = GND
  DQ20_B  = M_E_CPU0_SB_DQ<20>
  VSS57  = GND
  DQ21_B  = M_E_CPU0_SB_DQ<21>
  VSS58  = GND
  DQ24_B  = M_E_CPU0_SB_DQ<24>
  VSS59  = GND
  DQ25_B  = M_E_CPU0_SB_DQ<25>
  VSS60  = GND
  DQS3_B_T  = M_E_CPU0_SB_DQS_DP<3>
  DQS3_B_C  = M_E_CPU0_SB_DQS_DN<3>
  VSS61  = GND
  DQ28_B  = M_E_CPU0_SB_DQ<28>
  VSS62  = GND
  DQ29_B  = M_E_CPU0_SB_DQ<29>
  VSS63  = GND
  RFU1  = TP_CHE_CPU0_DIMM1_FRU_1
  VIN_BULK1  = P12V_S3_AUX_CPU0_NVDIMM
  VIN_BULK2  = P12V_S3_AUX_CPU0_NVDIMM
  \pwr_good||fail_n\  = PWRGD_CHE_CPU0_DIMM1
  HSA  = PD_CHE_CPU0_DIMM1_SAA
  RFU2  = TP_CHE_CPU0_DIMM1_FRU_2
  RFU3  = TP_CHE_CPU0_DIMM1_FRU_3
  VSS64  = GND
  DQ2_A  = M_E_CPU0_SA_DQ<2>
  VSS65  = GND
  DQ3_A  = M_E_CPU0_SA_DQ<3>
  VSS66  = GND
  \dqs5_a_c||tdqs5_a_c||dqs5_a_t||tdqs5_a_t\  = M_E_CPU0_SA_DQS_DN<5>
  \dqs5_a_t||tdqs5_a_t\  = M_E_CPU0_SA_DQS_DP<5>
  VSS67  = GND
  DQ6_A  = M_E_CPU0_SA_DQ<6>
  VSS68  = GND
  DQ7_A  = M_E_CPU0_SA_DQ<7>
  VSS69  = GND
  DQ10_A  = M_E_CPU0_SA_DQ<10>
  VSS70  = GND
  DQ11_A  = M_E_CPU0_SA_DQ<11>
  VSS71  = GND
  \dqs6_a_c||tdqs6_a_c||dqs6_a_t||tdqs6_a_t\  = M_E_CPU0_SA_DQS_DN<6>
  \dqs6_a_t||tdqs6_a_t\  = M_E_CPU0_SA_DQS_DP<6>
  VSS72  = GND
  DQ14_A  = M_E_CPU0_SA_DQ<14>
  VSS73  = GND
  DQ15_A  = M_E_CPU0_SA_DQ<15>
  VSS74  = GND
  DQ18_A  = M_E_CPU0_SA_DQ<18>
  VSS75  = GND
  DQ19_A  = M_E_CPU0_SA_DQ<19>
  VSS76  = GND
  \dqs7_a_c||tdqs7_a_c\  = M_E_CPU0_SA_DQS_DN<7>
  \dqs7_a_t||tdqs7_a_t\  = M_E_CPU0_SA_DQS_DP<7>
  VSS77  = GND
  DQ22_A  = M_E_CPU0_SA_DQ<22>
  VSS78  = GND
  DQ23_A  = M_E_CPU0_SA_DQ<23>
  VSS79  = GND
  DQ26_A  = M_E_CPU0_SA_DQ<26>
  VSS80  = GND
  DQ27_A  = M_E_CPU0_SA_DQ<27>
  VSS81  = GND
  \dqs8_a_c||tdqs8_a_c\  = M_E_CPU0_SA_DQS_DN<8>
  \dqs8_a_t||tdqs8_a_t\  = M_E_CPU0_SA_DQS_DP<8>
  VSS82  = GND
  DQ30_A  = M_E_CPU0_SA_DQ<30>
  VSS83  = GND
  DQ31_A  = M_E_CPU0_SA_DQ<31>
  VSS84  = GND
  CB2_A  = M_E_CPU0_SA_CB<2>
  VSS85  = GND
  CB3_A  = M_E_CPU0_SA_CB<3>
  VSS86  = GND
  \dqs9_a_c||tdqs9_a_c\  = M_E_CPU0_SA_DQS_DN<9>
  \dqs9_a_t||tdqs9_a_t\  = M_E_CPU0_SA_DQS_DP<9>
  VSS87  = GND
  CB6_A  = M_E_CPU0_SA_CB<6>
  VSS88  = GND
  CB7_A  = M_E_CPU0_SA_CB<7>
  VSS89  = GND
  RESET_N  = RST_M_EF_CPU0_FPGA_N
  VSS90  = GND
  CS1_A_N  = M_E_CPU0_SA_CS_N<1>
  VSS91  = GND
  CA1_A  = M_E_CPU0_SA_CA<1>
  VSS92  = GND
  CA3_A  = M_E_CPU0_SA_CA<3>
  VSS93  = GND
  CA5_A  = M_E_CPU0_SA_CA<5>
  VSS94  = GND
  CK_T  = M_E_CPU0_CLK_DP<0>
  CK_C  = M_E_CPU0_CLK_DN<0>
  VSS95  = GND
  RFU4  = TP_CHE_CPU0_DIMM1_FRU_4
  CA1_B  = M_E_CPU0_SB_CA<1>
  VSS96  = GND
  CA3_B  = M_E_CPU0_SB_CA<3>
  VSS97  = GND
  CA5_B  = M_E_CPU0_SB_CA<5>
  VSS98  = GND
  PAR_B  = M_E_CPU0_SB_PAR
  VSS99  = GND
  CS1_B_N  = M_E_CPU0_SB_CS_N<1>
  VSS100  = GND
  RFU5  = TP_CHE_CPU0_DIMM1_FRU_5
  RFU6  = TP_CHE_CPU0_DIMM1_FRU_6
  VSS101  = GND
  CB6_B  = M_E_CPU0_SB_CB<6>
  VSS102  = GND
  CB7_B  = M_E_CPU0_SB_CB<7>
  VSS103  = GND
  DQS4_B_C  = M_E_CPU0_SB_DQS_DN<4>
  DQS4_B_T  = M_E_CPU0_SB_DQS_DP<4>
  VSS104  = GND
  CB2_B  = M_E_CPU0_SB_CB<2>
  VSS105  = GND
  CB3_B  = M_E_CPU0_SB_CB<3>
  VSS106  = GND
  DQ2_B  = M_E_CPU0_SB_DQ<2>
  VSS107  = GND
  DQ3_B  = M_E_CPU0_SB_DQ<3>
  VSS108  = GND
  \dqs5_b_c||tdqs5_b_c\  = M_E_CPU0_SB_DQS_DN<5>
  \dqs5_b_t||tdqs5_b_t\  = M_E_CPU0_SB_DQS_DP<5>
  VSS109  = GND
  DQ6_B  = M_E_CPU0_SB_DQ<6>
  VSS110  = GND
  DQ7_B  = M_E_CPU0_SB_DQ<7>
  VSS111  = GND
  DQ10_B  = M_E_CPU0_SB_DQ<10>
  VSS112  = GND
  DQ11_B  = M_E_CPU0_SB_DQ<11>
  VSS113  = GND
  \dqs6_b_c||tdqs6_b_c\  = M_E_CPU0_SB_DQS_DN<6>
  \dqs6_b_t||tdqs6_b_t\  = M_E_CPU0_SB_DQS_DP<6>
  VSS114  = GND
  DQ14_B  = M_E_CPU0_SB_DQ<14>
  VSS115  = GND
  DQ15_B  = M_E_CPU0_SB_DQ<15>
  VSS116  = GND
  DQ18_B  = M_E_CPU0_SB_DQ<18>
  VSS117  = GND
  DQ19_B  = M_E_CPU0_SB_DQ<19>
  VSS118  = GND
  \dqs7_b_c||tdqs7_b_c\  = M_E_CPU0_SB_DQS_DN<7>
  \dqs7_b_t||tdqs7_b_t\  = M_E_CPU0_SB_DQS_DP<7>
  VSS119  = GND
  DQ22_B  = M_E_CPU0_SB_DQ<22>
  VSS120  = GND
  DQ23_B  = M_E_CPU0_SB_DQ<23>
  VSS121  = GND
  DQ26_B  = M_E_CPU0_SB_DQ<26>
  VSS122  = GND
  DQ27_B  = M_E_CPU0_SB_DQ<27>
  VSS123  = GND
  \dqs8_b_c||tdqs8_b_c\  = M_E_CPU0_SB_DQS_DN<8>
  \dqs8_b_t||tdqs8_b_t\  = M_E_CPU0_SB_DQS_DP<8>
  VSS124  = GND
  DQ30_B  = M_E_CPU0_SB_DQ<30>
  VSS125  = GND
  DQ31_B  = M_E_CPU0_SB_DQ<31>
  VSS126  = GND
  G1  = GND
  G2  = GND
  G3  = GND

(kicad_pcb
	(version 20260206)
	(generator "pcbnew")
	(generator_version "10.0")
	(general
		(thickness 1.6)
		(legacy_teardrops no)
	)
	(paper "A4")
	(title_block
		(title "03242023_DA0F0TMBIJ0_F0T_Motherboard_J_brd_V01_OCP.brd")
		(comment 1 "Grand Teton / footprint 461 of 6105 (J9), pads 1-45 of 291")
	)
	(layers
		(0 "F.Cu" signal "TOP")
		(4 "In1.Cu" signal "GND")
		(6 "In2.Cu" signal "IN1")
		(8 "In3.Cu" signal "GND1")
		(10 "In4.Cu" signal "IN2")
		(12 "In5.Cu" signal "GND2")
		(14 "In6.Cu" signal "IN3")
		(16 "In7.Cu" signal "GND3")
		(18 "In8.Cu" signal "VCC")
		(20 "In9.Cu" signal "VCC1")
		(22 "In10.Cu" signal "GND4")
		(24 "In11.Cu" signal "IN4")
		(26 "In12.Cu" signal "GND5")
		(28 "In13.Cu" signal "IN5")
		(30 "In14.Cu" signal "GND6")
		(32 "In15.Cu" signal "IN6")
		(34 "In16.Cu" signal "GND7")
		(2 "B.Cu" signal "BOTTOM")
		(9 "F.Adhes" user "F.Adhesive")
		(11 "B.Adhes" user "B.Adhesive")
		(13 "F.Paste" user "Package Geometry/Pastemask Top")
		(15 "B.Paste" user "Package Geometry/Pastemask Bottom")
		(5 "F.SilkS" user "Ref Des/Silkscreen Top")
		(7 "B.SilkS" user "Ref Des/Silkscreen Bottom")
		(1 "F.Mask" user "Board Geometry/Soldermask Top")
		(3 "B.Mask" user "Board Geometry/Soldermask Bottom")
		(17 "Dwgs.User" user "User.Drawings")
		(19 "Cmts.User" user "User.Comments")
		(21 "Eco1.User" user "User.Eco1")
		(23 "Eco2.User" user "User.Eco2")
		(25 "Edge.Cuts" user "Board Geometry/Outline")
		(27 "Margin" user)
		(31 "F.CrtYd" user "Package Geometry/Place Bound Top")
		(29 "B.CrtYd" user "Package Geometry/Place Bound Bottom")
		(35 "F.Fab" user "Ref Des/Assembly Top")
		(33 "B.Fab" user "Ref Des/Assembly Bottom")
	)
	(footprint ""
		(layer "F.Cu")
		(at 416.347148 -258.091686)
		(property "Reference" "J9"
			(at -3.683 -81.702148 0)
			(unlocked yes)
			(layer "F.SilkS")
			(effects
				(font
					(size 0.7874 0.5842)
					(thickness 0.1524)
				)
				(justify left)
			)
		)
		(property "Value" ""
			(at 0 0 0)
			(layer "F.Fab")
			(effects
				(font
					(size 1.27 1.27)
				)
			)
		)
		(duplicate_pad_numbers_are_jumpers no)
		(pad "1" smd rect
			(at -2.050034 -63.324994 270)
			(size 0.519938 1.4986)
			(layers "F.Cu" "F.Mask" "F.Paste")
			(net "P12V_S3_AUX_CPU0_NVDIMM")
		)
		(pad "2" smd rect
			(at -2.050034 -62.47511 270)
			(size 0.519938 1.4986)
			(layers "F.Cu" "F.Mask" "F.Paste")
			(net "TP_CHE_CPU0_DIMM1_FRU_0")
		)
		(pad "3" smd rect
			(at -2.050034 -61.624972 270)
			(size 0.519938 1.4986)
			(layers "F.Cu" "F.Mask" "F.Paste")
			(net "P3V3_AUX")
		)
		(pad "4" smd rect
			(at -2.050034 -60.775088 270)
			(size 0.519938 1.4986)
			(layers "F.Cu" "F.Mask" "F.Paste")
			(net "I3C_SPD_DDREFGH_CPU0_LVC1_SCL_R")
		)
		(pad "5" smd rect
			(at -2.050034 -59.92495 270)
			(size 0.519938 1.4986)
			(layers "F.Cu" "F.Mask" "F.Paste")
			(net "I3C_SPD_DDREFGH_CPU0_LVC1_SDA")
		)
		(pad "6" smd rect
			(at -2.050034 -59.075066 270)
			(size 0.519938 1.4986)
			(layers "F.Cu" "F.Mask" "F.Paste")
			(net "GND")
		)
		(pad "7" smd rect
			(at -2.050034 -58.224928 270)
			(size 0.519938 1.4986)
			(layers "F.Cu" "F.Mask" "F.Paste")
			(net "M_E_CPU0_SA_DQ<0>")
		)
		(pad "8" smd rect
			(at -2.050034 -57.375044 270)
			(size 0.519938 1.4986)
			(layers "F.Cu" "F.Mask" "F.Paste")
			(net "GND")
		)
		(pad "9" smd rect
			(at -2.050034 -56.524906 270)
			(size 0.519938 1.4986)
			(layers "F.Cu" "F.Mask" "F.Paste")
			(net "M_E_CPU0_SA_DQ<1>")
		)
		(pad "10" smd rect
			(at -2.050034 -55.675022 270)
			(size 0.519938 1.4986)
			(layers "F.Cu" "F.Mask" "F.Paste")
			(net "GND")
		)
		(pad "11" smd rect
			(at -2.050034 -54.824884 270)
			(size 0.519938 1.4986)
			(layers "F.Cu" "F.Mask" "F.Paste")
			(net "M_E_CPU0_SA_DQS_DP<0>")
		)
		(pad "12" smd rect
			(at -2.050034 -53.975 270)
			(size 0.519938 1.4986)
			(layers "F.Cu" "F.Mask" "F.Paste")
			(net "M_E_CPU0_SA_DQS_DN<0>")
		)
		(pad "13" smd rect
			(at -2.050034 -53.125116 270)
			(size 0.519938 1.4986)
			(layers "F.Cu" "F.Mask" "F.Paste")
			(net "GND")
		)
		(pad "14" smd rect
			(at -2.050034 -52.274978 270)
			(size 0.519938 1.4986)
			(layers "F.Cu" "F.Mask" "F.Paste")
			(net "M_E_CPU0_SA_DQ<4>")
		)
		(pad "15" smd rect
			(at -2.050034 -51.425094 270)
			(size 0.519938 1.4986)
			(layers "F.Cu" "F.Mask" "F.Paste")
			(net "GND")
		)
		(pad "16" smd rect
			(at -2.050034 -50.574956 270)
			(size 0.519938 1.4986)
			(layers "F.Cu" "F.Mask" "F.Paste")
			(net "M_E_CPU0_SA_DQ<5>")
		)
		(pad "17" smd rect
			(at -2.050034 -49.725072 270)
			(size 0.519938 1.4986)
			(layers "F.Cu" "F.Mask" "F.Paste")
			(net "GND")
		)
		(pad "18" smd rect
			(at -2.050034 -48.874934 270)
			(size 0.519938 1.4986)
			(layers "F.Cu" "F.Mask" "F.Paste")
			(net "M_E_CPU0_SA_DQ<8>")
		)
		(pad "19" smd rect
			(at -2.050034 -48.02505 270)
			(size 0.519938 1.4986)
			(layers "F.Cu" "F.Mask" "F.Paste")
			(net "GND")
		)
		(pad "20" smd rect
			(at -2.050034 -47.174912 270)
			(size 0.519938 1.4986)
			(layers "F.Cu" "F.Mask" "F.Paste")
			(net "M_E_CPU0_SA_DQ<9>")
		)
		(pad "21" smd rect
			(at -2.050034 -46.325028 270)
			(size 0.519938 1.4986)
			(layers "F.Cu" "F.Mask" "F.Paste")
			(net "GND")
		)
		(pad "22" smd rect
			(at -2.050034 -45.47489 270)
			(size 0.519938 1.4986)
			(layers "F.Cu" "F.Mask" "F.Paste")
			(net "M_E_CPU0_SA_DQS_DP<1>")
		)
		(pad "23" smd rect
			(at -2.050034 -44.625006 270)
			(size 0.519938 1.4986)
			(layers "F.Cu" "F.Mask" "F.Paste")
			(net "M_E_CPU0_SA_DQS_DN<1>")
		)
		(pad "24" smd rect
			(at -2.050034 -43.775122 270)
			(size 0.519938 1.4986)
			(layers "F.Cu" "F.Mask" "F.Paste")
			(net "GND")
		)
		(pad "25" smd rect
			(at -2.050034 -42.924984 270)
			(size 0.519938 1.4986)
			(layers "F.Cu" "F.Mask" "F.Paste")
			(net "M_E_CPU0_SA_DQ<12>")
		)
		(pad "26" smd rect
			(at -2.050034 -42.0751 270)
			(size 0.519938 1.4986)
			(layers "F.Cu" "F.Mask" "F.Paste")
			(net "GND")
		)
		(pad "27" smd rect
			(at -2.050034 -41.224962 270)
			(size 0.519938 1.4986)
			(layers "F.Cu" "F.Mask" "F.Paste")
			(net "M_E_CPU0_SA_DQ<13>")
		)
		(pad "28" smd rect
			(at -2.050034 -40.375078 270)
			(size 0.519938 1.4986)
			(layers "F.Cu" "F.Mask" "F.Paste")
			(net "GND")
		)
		(pad "29" smd rect
			(at -2.050034 -39.52494 270)
			(size 0.519938 1.4986)
			(layers "F.Cu" "F.Mask" "F.Paste")
			(net "M_E_CPU0_SA_DQ<16>")
		)
		(pad "30" smd rect
			(at -2.050034 -38.675056 270)
			(size 0.519938 1.4986)
			(layers "F.Cu" "F.Mask" "F.Paste")
			(net "GND")
		)
		(pad "31" smd rect
			(at -2.050034 -37.824918 270)
			(size 0.519938 1.4986)
			(layers "F.Cu" "F.Mask" "F.Paste")
			(net "M_E_CPU0_SA_DQ<17>")
		)
		(pad "32" smd rect
			(at -2.050034 -36.975034 270)
			(size 0.519938 1.4986)
			(layers "F.Cu" "F.Mask" "F.Paste")
			(net "GND")
		)
		(pad "33" smd rect
			(at -2.050034 -36.124896 270)
			(size 0.519938 1.4986)
			(layers "F.Cu" "F.Mask" "F.Paste")
			(net "M_E_CPU0_SA_DQS_DP<2>")
		)
		(pad "34" smd rect
			(at -2.050034 -35.275012 270)
			(size 0.519938 1.4986)
			(layers "F.Cu" "F.Mask" "F.Paste")
			(net "M_E_CPU0_SA_DQS_DN<2>")
		)
		(pad "35" smd rect
			(at -2.050034 -34.425128 270)
			(size 0.519938 1.4986)
			(layers "F.Cu" "F.Mask" "F.Paste")
			(net "GND")
		)
		(pad "36" smd rect
			(at -2.050034 -33.57499 270)
			(size 0.519938 1.4986)
			(layers "F.Cu" "F.Mask" "F.Paste")
			(net "M_E_CPU0_SA_DQ<20>")
		)
		(pad "37" smd rect
			(at -2.050034 -32.725106 270)
			(size 0.519938 1.4986)
			(layers "F.Cu" "F.Mask" "F.Paste")
			(net "GND")
		)
		(pad "38" smd rect
			(at -2.050034 -31.874968 270)
			(size 0.519938 1.4986)
			(layers "F.Cu" "F.Mask" "F.Paste")
			(net "M_E_CPU0_SA_DQ<21>")
		)
		(pad "39" smd rect
			(at -2.050034 -31.025084 270)
			(size 0.519938 1.4986)
			(layers "F.Cu" "F.Mask" "F.Paste")
			(net "GND")
		)
		(pad "40" smd rect
			(at -2.050034 -30.174946 270)
			(size 0.519938 1.4986)
			(layers "F.Cu" "F.Mask" "F.Paste")
			(net "M_E_CPU0_SA_DQ<24>")
		)
		(pad "41" smd rect
			(at -2.050034 -29.325062 270)
			(size 0.519938 1.4986)
			(layers "F.Cu" "F.Mask" "F.Paste")
			(net "GND")
		)
		(pad "42" smd rect
			(at -2.050034 -28.474924 270)
			(size 0.519938 1.4986)
			(layers "F.Cu" "F.Mask" "F.Paste")
			(net "M_E_CPU0_SA_DQ<25>")
		)
		(pad "43" smd rect
			(at -2.050034 -27.62504 270)
			(size 0.519938 1.4986)
			(layers "F.Cu" "F.Mask" "F.Paste")
			(net "GND")
		)
		(pad "44" smd rect
			(at -2.050034 -26.774902 270)
			(size 0.519938 1.4986)
			(layers "F.Cu" "F.Mask" "F.Paste")
			(net "M_E_CPU0_SA_DQS_DP<3>")
		)
		(pad "45" smd rect
			(at -2.050034 -25.925018 270)
			(size 0.519938 1.4986)
			(layers "F.Cu" "F.Mask" "F.Paste")
			(net "M_E_CPU0_SA_DQS_DN<3>")
		)
	)
)
